(kicad_pcb
	(version 20260206)
	(generator "pcbnew")
	(generator_version "10.0")
	(general
		(thickness 1.6)
		(legacy_teardrops no)
	)
	(paper "A4")
	(title_block
		(title "04192023_DAF0TMB3IC0_F0TG_MB_C_brd_V02_OCP.brd")
		(comment 1 "Grand Teton / footprints 3523-3530 of 8354")
	)
	(layers
		(0 "F.Cu" signal "TOP")
		(4 "In1.Cu" signal "GND")
		(6 "In2.Cu" signal "IN1")
		(8 "In3.Cu" signal "GND1")
		(10 "In4.Cu" signal "IN2")
		(12 "In5.Cu" signal "GND2")
		(14 "In6.Cu" signal "IN3")
		(16 "In7.Cu" signal "GND3")
		(18 "In8.Cu" signal "VCC")
		(20 "In9.Cu" signal "VCC1")
		(22 "In10.Cu" signal "GND4")
		(24 "In11.Cu" signal "IN4")
		(26 "In12.Cu" signal "GND5")
		(28 "In13.Cu" signal "IN5")
		(30 "In14.Cu" signal "GND6")
		(32 "In15.Cu" signal "IN6")
		(34 "In16.Cu" signal "GND7")
		(2 "B.Cu" signal "BOTTOM")
		(9 "F.Adhes" user "F.Adhesive")
		(11 "B.Adhes" user "B.Adhesive")
		(13 "F.Paste" user "Package Geometry/Pastemask Top")
		(15 "B.Paste" user "Package Geometry/Pastemask Bottom")
		(5 "F.SilkS" user "Ref Des/Silkscreen Top")
		(7 "B.SilkS" user "Ref Des/Silkscreen Bottom")
		(1 "F.Mask" user "Board Geometry/Soldermask Top")
		(3 "B.Mask" user "Board Geometry/Soldermask Bottom")
		(17 "Dwgs.User" user "User.Drawings")
		(19 "Cmts.User" user "User.Comments")
		(21 "Eco1.User" user "User.Eco1")
		(23 "Eco2.User" user "User.Eco2")
		(25 "Edge.Cuts" user "Board Geometry/Outline")
		(27 "Margin" user)
		(31 "F.CrtYd" user "Package Geometry/Place Bound Top")
		(29 "B.CrtYd" user "Package Geometry/Place Bound Bottom")
		(35 "F.Fab" user "Ref Des/Assembly Top")
		(33 "B.Fab" user "Ref Des/Assembly Bottom")
	)
	(footprint ""
		(layer "F.Cu")
		(at 254.592836 -121.71045)
		(property "Reference" "R3723"
			(at 0 0 0)
			(layer "F.SilkS")
			(hide yes)
			(effects
				(font
					(size 1.27 1.27)
				)
			)
		)
		(property "Value" ""
			(at 0 0 0)
			(layer "F.Fab")
			(effects
				(font
					(size 1.27 1.27)
				)
			)
		)
		(duplicate_pad_numbers_are_jumpers no)
		(fp_line
			(start -0.7874 -0.4064)
			(end 0.7874 -0.4064)
			(stroke
				(width 0.1524)
				(type default)
			)
			(layer "F.SilkS")
		)
		(fp_line
			(start -0.7874 0.4064)
			(end -0.7874 -0.4064)
			(stroke
				(width 0.1524)
				(type default)
			)
			(layer "F.SilkS")
		)
		(fp_line
			(start 0.7874 -0.4064)
			(end 0.7874 0.4064)
			(stroke
				(width 0.1524)
				(type default)
			)
			(layer "F.SilkS")
		)
		(fp_line
			(start 0.7874 0.4064)
			(end -0.7874 0.4064)
			(stroke
				(width 0.1524)
				(type default)
			)
			(layer "F.SilkS")
		)
		(fp_line
			(start -0.67945 -0.305054)
			(end -0.12065 -0.305054)
			(stroke
				(width 0.1)
				(type default)
			)
			(layer "F.Fab")
		)
		(fp_line
			(start -0.67945 0.3048)
			(end -0.67945 -0.305054)
			(stroke
				(width 0.1)
				(type default)
			)
			(layer "F.Fab")
		)
		(fp_line
			(start -0.12065 -0.305054)
			(end -0.12065 -0.2794)
			(stroke
				(width 0.1)
				(type default)
			)
			(layer "F.Fab")
		)
		(fp_line
			(start -0.12065 -0.2794)
			(end 0.12065 -0.2794)
			(stroke
				(width 0.1)
				(type default)
			)
			(layer "F.Fab")
		)
		(fp_line
			(start -0.12065 0.2794)
			(end -0.12065 0.3048)
			(stroke
				(width 0.1)
				(type default)
			)
			(layer "F.Fab")
		)
		(fp_line
			(start -0.12065 0.3048)
			(end -0.67945 0.3048)
			(stroke
				(width 0.1)
				(type default)
			)
			(layer "F.Fab")
		)
		(fp_line
			(start 0.120396 0.2794)
			(end -0.12065 0.2794)
			(stroke
				(width 0.1)
				(type default)
			)
			(layer "F.Fab")
		)
		(fp_line
			(start 0.120396 0.3048)
			(end 0.120396 0.2794)
			(stroke
				(width 0.1)
				(type default)
			)
			(layer "F.Fab")
		)
		(fp_line
			(start 0.12065 -0.3048)
			(end 0.67945 -0.3048)
			(stroke
				(width 0.1)
				(type default)
			)
			(layer "F.Fab")
		)
		(fp_line
			(start 0.12065 -0.2794)
			(end 0.12065 -0.3048)
			(stroke
				(width 0.1)
				(type default)
			)
			(layer "F.Fab")
		)
		(fp_line
			(start 0.67945 -0.3048)
			(end 0.67945 0.3048)
			(stroke
				(width 0.1)
				(type default)
			)
			(layer "F.Fab")
		)
		(fp_line
			(start 0.67945 0.3048)
			(end 0.120396 0.3048)
			(stroke
				(width 0.1)
				(type default)
			)
			(layer "F.Fab")
		)
		(pad "1" smd circle
			(at -0.40005 0)
			(size 0 0)
			(layers "F.Cu" "F.Mask" "F.Paste")
			(net "P3V3_AUX")
		)
		(pad "2" smd circle
			(at 0.40005 0)
			(size 0 0)
			(layers "F.Cu" "F.Mask" "F.Paste")
			(net "SMB_VR_3V3AUX_SCL")
		)
	)
	(footprint ""
		(layer "F.Cu")
		(at 118.618 -431.038)
		(property "Reference" "R3451"
			(at 0 0 0)
			(layer "F.SilkS")
			(hide yes)
			(effects
				(font
					(size 1.27 1.27)
				)
			)
		)
		(property "Value" ""
			(at 0 0 0)
			(layer "F.Fab")
			(effects
				(font
					(size 1.27 1.27)
				)
			)
		)
		(duplicate_pad_numbers_are_jumpers no)
		(fp_line
			(start -0.7874 -0.4064)
			(end 0.7874 -0.4064)
			(stroke
				(width 0.1524)
				(type default)
			)
			(layer "F.SilkS")
		)
		(fp_line
			(start -0.7874 0.4064)
			(end -0.7874 -0.4064)
			(stroke
				(width 0.1524)
				(type default)
			)
			(layer "F.SilkS")
		)
		(fp_line
			(start 0.7874 -0.4064)
			(end 0.7874 0.4064)
			(stroke
				(width 0.1524)
				(type default)
			)
			(layer "F.SilkS")
		)
		(fp_line
			(start 0.7874 0.4064)
			(end -0.7874 0.4064)
			(stroke
				(width 0.1524)
				(type default)
			)
			(layer "F.SilkS")
		)
		(fp_line
			(start -0.67945 -0.305054)
			(end -0.12065 -0.305054)
			(stroke
				(width 0.1)
				(type default)
			)
			(layer "F.Fab")
		)
		(fp_line
			(start -0.67945 0.3048)
			(end -0.67945 -0.305054)
			(stroke
				(width 0.1)
				(type default)
			)
			(layer "F.Fab")
		)
		(fp_line
			(start -0.12065 -0.305054)
			(end -0.12065 -0.2794)
			(stroke
				(width 0.1)
				(type default)
			)
			(layer "F.Fab")
		)
		(fp_line
			(start -0.12065 -0.2794)
			(end 0.12065 -0.2794)
			(stroke
				(width 0.1)
				(type default)
			)
			(layer "F.Fab")
		)
		(fp_line
			(start -0.12065 0.2794)
			(end -0.12065 0.3048)
			(stroke
				(width 0.1)
				(type default)
			)
			(layer "F.Fab")
		)
		(fp_line
			(start -0.12065 0.3048)
			(end -0.67945 0.3048)
			(stroke
				(width 0.1)
				(type default)
			)
			(layer "F.Fab")
		)
		(fp_line
			(start 0.120396 0.2794)
			(end -0.12065 0.2794)
			(stroke
				(width 0.1)
				(type default)
			)
			(layer "F.Fab")
		)
		(fp_line
			(start 0.120396 0.3048)
			(end 0.120396 0.2794)
			(stroke
				(width 0.1)
				(type default)
			)
			(layer "F.Fab")
		)
		(fp_line
			(start 0.12065 -0.3048)
			(end 0.67945 -0.3048)
			(stroke
				(width 0.1)
				(type default)
			)
			(layer "F.Fab")
		)
		(fp_line
			(start 0.12065 -0.2794)
			(end 0.12065 -0.3048)
			(stroke
				(width 0.1)
				(type default)
			)
			(layer "F.Fab")
		)
		(fp_line
			(start 0.67945 -0.3048)
			(end 0.67945 0.3048)
			(stroke
				(width 0.1)
				(type default)
			)
			(layer "F.Fab")
		)
		(fp_line
			(start 0.67945 0.3048)
			(end 0.120396 0.3048)
			(stroke
				(width 0.1)
				(type default)
			)
			(layer "F.Fab")
		)
		(pad "1" smd circle
			(at -0.40005 0)
			(size 0 0)
			(layers "F.Cu" "F.Mask" "F.Paste")
			(net "P3V3_AUX")
		)
		(pad "2" smd circle
			(at 0.40005 0)
			(size 0 0)
			(layers "F.Cu" "F.Mask" "F.Paste")
			(net "GPU_BASE_STBY_EN")
		)
	)
	(footprint ""
		(layer "F.Cu")
		(at 407.627582 -416.899344 -90)
		(property "Reference" "C6590"
			(at 0 0 270)
			(layer "F.SilkS")
			(hide yes)
			(effects
				(font
					(size 1.27 1.27)
				)
			)
		)
		(property "Value" ""
			(at 0 0 270)
			(layer "F.Fab")
			(effects
				(font
					(size 1.27 1.27)
				)
			)
		)
		(duplicate_pad_numbers_are_jumpers no)
		(fp_line
			(start -0.299974 0.150114)
			(end -0.299974 -0.150114)
			(stroke
				(width 0.1)
				(type default)
			)
			(layer "F.Fab")
		)
		(fp_line
			(start 0.299974 0.150114)
			(end -0.299974 0.150114)
			(stroke
				(width 0.1)
				(type default)
			)
			(layer "F.Fab")
		)
		(fp_line
			(start -0.299974 -0.150114)
			(end 0.299974 -0.150114)
			(stroke
				(width 0.1)
				(type default)
			)
			(layer "F.Fab")
		)
		(fp_line
			(start 0.299974 -0.150114)
			(end 0.299974 0.150114)
			(stroke
				(width 0.1)
				(type default)
			)
			(layer "F.Fab")
		)
		(pad "1" smd rect
			(at -0.2667 0 270)
			(size 0.3048 0.381)
			(layers "F.Cu" "F.Mask" "F.Paste")
			(net "P5E_CPU0_P2_TX_BUF_C_DN<12>")
		)
		(pad "2" smd rect
			(at 0.2667 0 270)
			(size 0.3048 0.381)
			(layers "F.Cu" "F.Mask" "F.Paste")
			(net "P5E_CPU0_P2_TX_BUF_DN<12>")
		)
	)
	(footprint ""
		(layer "F.Cu")
		(at 88.505284 -408.517344 -90)
		(property "Reference" "C6655"
			(at 0 0 270)
			(layer "F.SilkS")
			(hide yes)
			(effects
				(font
					(size 1.27 1.27)
				)
			)
		)
		(property "Value" ""
			(at 0 0 270)
			(layer "F.Fab")
			(effects
				(font
					(size 1.27 1.27)
				)
			)
		)
		(duplicate_pad_numbers_are_jumpers no)
		(fp_line
			(start -0.299974 0.150114)
			(end -0.299974 -0.150114)
			(stroke
				(width 0.1)
				(type default)
			)
			(layer "F.Fab")
		)
		(fp_line
			(start 0.299974 0.150114)
			(end -0.299974 0.150114)
			(stroke
				(width 0.1)
				(type default)
			)
			(layer "F.Fab")
		)
		(fp_line
			(start -0.299974 -0.150114)
			(end 0.299974 -0.150114)
			(stroke
				(width 0.1)
				(type default)
			)
			(layer "F.Fab")
		)
		(fp_line
			(start 0.299974 -0.150114)
			(end 0.299974 0.150114)
			(stroke
				(width 0.1)
				(type default)
			)
			(layer "F.Fab")
		)
		(pad "1" smd rect
			(at -0.2667 0 270)
			(size 0.3048 0.381)
			(layers "F.Cu" "F.Mask" "F.Paste")
			(net "P5E_CPU1_P0_TX_BUF_C_DP<13>")
		)
		(pad "2" smd rect
			(at 0.2667 0 270)
			(size 0.3048 0.381)
			(layers "F.Cu" "F.Mask" "F.Paste")
			(net "P5E_CPU1_P0_TX_BUF_DP<13>")
		)
	)
	(footprint ""
		(layer "F.Cu")
		(at 9.74471 -79.480664)
		(property "Reference" "R3133"
			(at 0 0 0)
			(layer "F.SilkS")
			(hide yes)
			(effects
				(font
					(size 1.27 1.27)
				)
			)
		)
		(property "Value" ""
			(at 0 0 0)
			(layer "F.Fab")
			(effects
				(font
					(size 1.27 1.27)
				)
			)
		)
		(duplicate_pad_numbers_are_jumpers no)
		(fp_line
			(start -0.7874 -0.4064)
			(end 0.7874 -0.4064)
			(stroke
				(width 0.1524)
				(type default)
			)
			(layer "F.SilkS")
		)
		(fp_line
			(start -0.7874 0.4064)
			(end -0.7874 -0.4064)
			(stroke
				(width 0.1524)
				(type default)
			)
			(layer "F.SilkS")
		)
		(fp_line
			(start 0.7874 -0.4064)
			(end 0.7874 0.4064)
			(stroke
				(width 0.1524)
				(type default)
			)
			(layer "F.SilkS")
		)
		(fp_line
			(start 0.7874 0.4064)
			(end -0.7874 0.4064)
			(stroke
				(width 0.1524)
				(type default)
			)
			(layer "F.SilkS")
		)
		(fp_line
			(start -0.67945 -0.305054)
			(end -0.12065 -0.305054)
			(stroke
				(width 0.1)
				(type default)
			)
			(layer "F.Fab")
		)
		(fp_line
			(start -0.67945 0.3048)
			(end -0.67945 -0.305054)
			(stroke
				(width 0.1)
				(type default)
			)
			(layer "F.Fab")
		)
		(fp_line
			(start -0.12065 -0.305054)
			(end -0.12065 -0.2794)
			(stroke
				(width 0.1)
				(type default)
			)
			(layer "F.Fab")
		)
		(fp_line
			(start -0.12065 -0.2794)
			(end 0.12065 -0.2794)
			(stroke
				(width 0.1)
				(type default)
			)
			(layer "F.Fab")
		)
		(fp_line
			(start -0.12065 0.2794)
			(end -0.12065 0.3048)
			(stroke
				(width 0.1)
				(type default)
			)
			(layer "F.Fab")
		)
		(fp_line
			(start -0.12065 0.3048)
			(end -0.67945 0.3048)
			(stroke
				(width 0.1)
				(type default)
			)
			(layer "F.Fab")
		)
		(fp_line
			(start 0.120396 0.2794)
			(end -0.12065 0.2794)
			(stroke
				(width 0.1)
				(type default)
			)
			(layer "F.Fab")
		)
		(fp_line
			(start 0.120396 0.3048)
			(end 0.120396 0.2794)
			(stroke
				(width 0.1)
				(type default)
			)
			(layer "F.Fab")
		)
		(fp_line
			(start 0.12065 -0.3048)
			(end 0.67945 -0.3048)
			(stroke
				(width 0.1)
				(type default)
			)
			(layer "F.Fab")
		)
		(fp_line
			(start 0.12065 -0.2794)
			(end 0.12065 -0.3048)
			(stroke
				(width 0.1)
				(type default)
			)
			(layer "F.Fab")
		)
		(fp_line
			(start 0.67945 -0.3048)
			(end 0.67945 0.3048)
			(stroke
				(width 0.1)
				(type default)
			)
			(layer "F.Fab")
		)
		(fp_line
			(start 0.67945 0.3048)
			(end 0.120396 0.3048)
			(stroke
				(width 0.1)
				(type default)
			)
			(layer "F.Fab")
		)
		(pad "1" smd circle
			(at -0.40005 0)
			(size 0 0)
			(layers "F.Cu" "F.Mask" "F.Paste")
			(net "P3V3_AUX")
		)
		(pad "2" smd circle
			(at 0.40005 0)
			(size 0 0)
			(layers "F.Cu" "F.Mask" "F.Paste")
			(net "OCP_V3_2_PRSNT0_R_N")
		)
	)
	(footprint ""
		(layer "F.Cu")
		(at 323.374512 -409.15082 180)
		(property "Reference" "C7000"
			(at -5.053076 -1.373632 0)
			(unlocked yes)
			(layer "F.SilkS")
			(effects
				(font
					(size 0.7874 0.5842)
					(thickness 0.1524)
				)
				(justify left)
			)
		)
		(property "Value" ""
			(at 0 0 180)
			(layer "F.Fab")
			(effects
				(font
					(size 1.27 1.27)
				)
			)
		)
		(duplicate_pad_numbers_are_jumpers no)
		(fp_line
			(start 4.53898 2.15011)
			(end -4.53898 2.15011)
			(stroke
				(width 0.1524)
				(type default)
			)
			(layer "F.SilkS")
		)
		(fp_line
			(start 4.53898 -2.15011)
			(end 4.53898 2.15011)
			(stroke
				(width 0.1524)
				(type default)
			)
			(layer "F.SilkS")
		)
		(fp_line
			(start -4.53898 2.15011)
			(end -4.53898 -2.15011)
			(stroke
				(width 0.1524)
				(type default)
			)
			(layer "F.SilkS")
		)
		(fp_line
			(start -4.53898 -2.15011)
			(end 4.53898 -2.15011)
			(stroke
				(width 0.1524)
				(type default)
			)
			(layer "F.SilkS")
		)
		(fp_line
			(start -4.53898 -2.150618)
			(end -4.539742 2.152142)
			(stroke
				(width 0.1524)
				(type default)
			)
			(layer "F.SilkS")
		)
		(fp_line
			(start -4.69138 -2.150618)
			(end -4.692396 2.161032)
			(stroke
				(width 0.1524)
				(type default)
			)
			(layer "F.SilkS")
		)
		(fp_line
			(start -4.83108 2.150364)
			(end -4.447794 2.149348)
			(stroke
				(width 0.1524)
				(type default)
			)
			(layer "F.SilkS")
		)
		(fp_line
			(start -4.84378 -2.150618)
			(end -4.53898 -2.150618)
			(stroke
				(width 0.1524)
				(type default)
			)
			(layer "F.SilkS")
		)
		(fp_line
			(start -4.84378 -2.150618)
			(end -4.842256 2.163064)
			(stroke
				(width 0.1524)
				(type default)
			)
			(layer "F.SilkS")
		)
		(fp_line
			(start 3.64998 2.15011)
			(end -3.64998 2.15011)
			(stroke
				(width 0.1)
				(type default)
			)
			(layer "F.Fab")
		)
		(fp_line
			(start 3.64998 -2.15011)
			(end 3.64998 2.15011)
			(stroke
				(width 0.1)
				(type default)
			)
			(layer "F.Fab")
		)
		(fp_line
			(start -3.64998 2.15011)
			(end -3.64998 -2.15011)
			(stroke
				(width 0.1)
				(type default)
			)
			(layer "F.Fab")
		)
		(fp_line
			(start -3.64998 -2.15011)
			(end 3.64998 -2.15011)
			(stroke
				(width 0.1)
				(type default)
			)
			(layer "F.Fab")
		)
		(fp_text user "-"
			(at 6.26745 2.685288 0)
			(unlocked yes)
			(layer "F.SilkS")
			(effects
				(font
					(size 1.905 1.4224)
					(thickness 0.1524)
				)
				(justify left)
			)
		)
		(fp_text user "+"
			(at -4.515612 2.609342 180)
			(unlocked yes)
			(layer "F.SilkS")
			(effects
				(font
					(size 1.905 1.4224)
					(thickness 0.1524)
				)
				(justify left)
			)
		)
		(fp_text user "-"
			(at 4.313174 -0.094488 180)
			(unlocked yes)
			(layer "F.Fab")
			(effects
				(font
					(size 1.905 1.4224)
					(thickness 0.1524)
				)
				(justify left)
			)
		)
		(fp_text user "+"
			(at -6.214872 -0.337058 180)
			(unlocked yes)
			(layer "F.Fab")
			(effects
				(font
					(size 1.905 1.4224)
					(thickness 0.1524)
				)
				(justify left)
			)
		)
		(pad "1" smd rect
			(at -3.199892 0 180)
			(size 2.413 2.8194)
			(layers "F.Cu" "F.Mask" "F.Paste")
			(net "P0V9_CPU0_RT_2D")
		)
		(pad "2" smd rect
			(at 3.199892 0 180)
			(size 2.413 2.8194)
			(layers "F.Cu" "F.Mask" "F.Paste")
			(net "GND")
		)
	)
	(footprint ""
		(layer "F.Cu")
		(at 400.315684 -402.548852 -90)
		(property "Reference" "R1062"
			(at 0 0 270)
			(layer "F.SilkS")
			(hide yes)
			(effects
				(font
					(size 1.27 1.27)
				)
			)
		)
		(property "Value" ""
			(at 0 0 270)
			(layer "F.Fab")
			(effects
				(font
					(size 1.27 1.27)
				)
			)
		)
		(duplicate_pad_numbers_are_jumpers no)
		(fp_line
			(start -0.32512 0.175006)
			(end -0.32512 -0.175006)
			(stroke
				(width 0.1)
				(type default)
			)
			(layer "F.Fab")
		)
		(fp_line
			(start 0.32512 0.175006)
			(end -0.32512 0.175006)
			(stroke
				(width 0.1)
				(type default)
			)
			(layer "F.Fab")
		)
		(fp_line
			(start -0.32512 -0.175006)
			(end 0.32512 -0.175006)
			(stroke
				(width 0.1)
				(type default)
			)
			(layer "F.Fab")
		)
		(fp_line
			(start 0.32512 -0.175006)
			(end 0.32512 0.175006)
			(stroke
				(width 0.1)
				(type default)
			)
			(layer "F.Fab")
		)
		(pad "1" smd rect
			(at -0.2667 0 270)
			(size 0.3048 0.381)
			(layers "F.Cu" "F.Mask" "F.Paste")
			(net "RST_RT_CPU0_P2_RESET_R_N")
		)
		(pad "2" smd rect
			(at 0.2667 0 90)
			(size 0.3048 0.381)
			(layers "F.Cu" "F.Mask" "F.Paste")
			(net "GND")
		)
	)
	(footprint ""
		(layer "F.Cu")
		(at 365.794798 -428.28591 180)
		(property "Reference" "R684"
			(at 0 0 180)
			(layer "F.SilkS")
			(hide yes)
			(effects
				(font
					(size 1.27 1.27)
				)
			)
		)
		(property "Value" ""
			(at 0 0 180)
			(layer "F.Fab")
			(effects
				(font
					(size 1.27 1.27)
				)
			)
		)
		(duplicate_pad_numbers_are_jumpers no)
		(fp_line
			(start 0.32512 0.175006)
			(end -0.32512 0.175006)
			(stroke
				(width 0.1)
				(type default)
			)
			(layer "F.Fab")
		)
		(fp_line
			(start 0.32512 -0.175006)
			(end 0.32512 0.175006)
			(stroke
				(width 0.1)
				(type default)
			)
			(layer "F.Fab")
		)
		(fp_line
			(start -0.32512 0.175006)
			(end -0.32512 -0.175006)
			(stroke
				(width 0.1)
				(type default)
			)
			(layer "F.Fab")
		)
		(fp_line
			(start -0.32512 -0.175006)
			(end 0.32512 -0.175006)
			(stroke
				(width 0.1)
				(type default)
			)
			(layer "F.Fab")
		)
		(pad "1" smd rect
			(at -0.2667 0 180)
			(size 0.3048 0.381)
			(layers "F.Cu" "F.Mask" "F.Paste")
			(net "SMB_RT_CPU0_P3_ROM_MUX_1D_SCL")
		)
		(pad "2" smd rect
			(at 0.2667 0)
			(size 0.3048 0.381)
			(layers "F.Cu" "F.Mask" "F.Paste")
			(net "SMB_RT_CPU0_P3_ROM_MUX_1D_R_SCL")
		)
	)
)
